# T6G (Grand Teton) — schematic netlist excerpt (pin names and nets, part order shuffled) for the footprints in the layout excerpt that follows; sources: Cadence DE-HDL packaged netlist, KiCad conversion of 04192023_DAF0TMB3IC0_F0TG_MB_C_brd_V02_OCP.brd

R928  Q_RES  0 5% CHIP  pkg 0402LF  page 54 : A = CPU1_XTRIG_R2_L7 ; B = CPU1_XTRIG_L7
PR374  Q_RES  0 5% CHIP  pkg 0402LF  page 223 : A = PVDDIO_P1_VOS3 ; B = PVDDIO_P1

(kicad_pcb
	(version 20260206)
	(generator "pcbnew")
	(generator_version "10.0")
	(general
		(thickness 1.6)
		(legacy_teardrops no)
	)
	(paper "A4")
	(title_block
		(title "04192023_DAF0TMB3IC0_F0TG_MB_C_brd_V02_OCP.brd")
		(comment 1 "Grand Teton / footprints 5602-5603 of 8354")
	)
	(layers
		(0 "F.Cu" signal "TOP")
		(4 "In1.Cu" signal "GND")
		(6 "In2.Cu" signal "IN1")
		(8 "In3.Cu" signal "GND1")
		(10 "In4.Cu" signal "IN2")
		(12 "In5.Cu" signal "GND2")
		(14 "In6.Cu" signal "IN3")
		(16 "In7.Cu" signal "GND3")
		(18 "In8.Cu" signal "VCC")
		(20 "In9.Cu" signal "VCC1")
		(22 "In10.Cu" signal "GND4")
		(24 "In11.Cu" signal "IN4")
		(26 "In12.Cu" signal "GND5")
		(28 "In13.Cu" signal "IN5")
		(30 "In14.Cu" signal "GND6")
		(32 "In15.Cu" signal "IN6")
		(34 "In16.Cu" signal "GND7")
		(2 "B.Cu" signal "BOTTOM")
		(9 "F.Adhes" user "F.Adhesive")
		(11 "B.Adhes" user "B.Adhesive")
		(13 "F.Paste" user "Package Geometry/Pastemask Top")
		(15 "B.Paste" user "Package Geometry/Pastemask Bottom")
		(5 "F.SilkS" user "Ref Des/Silkscreen Top")
		(7 "B.SilkS" user "Ref Des/Silkscreen Bottom")
		(1 "F.Mask" user "Board Geometry/Soldermask Top")
		(3 "B.Mask" user "Board Geometry/Soldermask Bottom")
		(17 "Dwgs.User" user "User.Drawings")
		(19 "Cmts.User" user "User.Comments")
		(21 "Eco1.User" user "User.Eco1")
		(23 "Eco2.User" user "User.Eco2")
		(25 "Edge.Cuts" user "Board Geometry/Outline")
		(27 "Margin" user)
		(31 "F.CrtYd" user "Package Geometry/Place Bound Top")
		(29 "B.CrtYd" user "Package Geometry/Place Bound Bottom")
		(35 "F.Fab" user "Ref Des/Assembly Top")
		(33 "B.Fab" user "Ref Des/Assembly Bottom")
	)
	(footprint ""
		(layer "B.Cu")
		(at 33.219644 -349.386398 -90)
		(property "Reference" "PR374"
			(at 0 0 90)
			(layer "B.SilkS")
			(hide yes)
			(effects
				(font
					(size 1.27 1.27)
				)
				(justify mirror)
			)
		)
		(property "Value" ""
			(at 0 0 90)
			(layer "B.Fab")
			(effects
				(font
					(size 1.27 1.27)
				)
				(justify mirror)
			)
		)
		(duplicate_pad_numbers_are_jumpers no)
		(fp_line
			(start -0.7874 0.4064)
			(end 0.7874 0.4064)
			(stroke
				(width 0.1524)
				(type default)
			)
			(layer "B.SilkS")
		)
		(fp_line
			(start 0.7874 0.4064)
			(end 0.7874 -0.4064)
			(stroke
				(width 0.1524)
				(type default)
			)
			(layer "B.SilkS")
		)
		(fp_line
			(start -0.7874 -0.4064)
			(end -0.7874 0.4064)
			(stroke
				(width 0.1524)
				(type default)
			)
			(layer "B.SilkS")
		)
		(fp_line
			(start 0.7874 -0.4064)
			(end -0.7874 -0.4064)
			(stroke
				(width 0.1524)
				(type default)
			)
			(layer "B.SilkS")
		)
		(fp_line
			(start -0.67945 0.3048)
			(end -0.120396 0.3048)
			(stroke
				(width 0.1)
				(type default)
			)
			(layer "B.Fab")
		)
		(fp_line
			(start -0.120396 0.3048)
			(end -0.120396 0.2794)
			(stroke
				(width 0.1)
				(type default)
			)
			(layer "B.Fab")
		)
		(fp_line
			(start 0.12065 0.3048)
			(end 0.67945 0.3048)
			(stroke
				(width 0.1)
				(type default)
			)
			(layer "B.Fab")
		)
		(fp_line
			(start 0.67945 0.3048)
			(end 0.67945 -0.305054)
			(stroke
				(width 0.1)
				(type default)
			)
			(layer "B.Fab")
		)
		(fp_line
			(start -0.120396 0.2794)
			(end 0.12065 0.2794)
			(stroke
				(width 0.1)
				(type default)
			)
			(layer "B.Fab")
		)
		(fp_line
			(start 0.12065 0.2794)
			(end 0.12065 0.3048)
			(stroke
				(width 0.1)
				(type default)
			)
			(layer "B.Fab")
		)
		(fp_line
			(start -0.12065 -0.2794)
			(end -0.12065 -0.3048)
			(stroke
				(width 0.1)
				(type default)
			)
			(layer "B.Fab")
		)
		(fp_line
			(start 0.12065 -0.2794)
			(end -0.12065 -0.2794)
			(stroke
				(width 0.1)
				(type default)
			)
			(layer "B.Fab")
		)
		(fp_line
			(start -0.67945 -0.3048)
			(end -0.67945 0.3048)
			(stroke
				(width 0.1)
				(type default)
			)
			(layer "B.Fab")
		)
		(fp_line
			(start -0.12065 -0.3048)
			(end -0.67945 -0.3048)
			(stroke
				(width 0.1)
				(type default)
			)
			(layer "B.Fab")
		)
		(fp_line
			(start 0.12065 -0.305054)
			(end 0.12065 -0.2794)
			(stroke
				(width 0.1)
				(type default)
			)
			(layer "B.Fab")
		)
		(fp_line
			(start 0.67945 -0.305054)
			(end 0.12065 -0.305054)
			(stroke
				(width 0.1)
				(type default)
			)
			(layer "B.Fab")
		)
		(pad "1" smd circle
			(at 0.40005 0 90)
			(size 0 0)
			(layers "B.Cu" "B.Mask" "B.Paste")
			(net "PVDDIO_P1_VOS3")
		)
		(pad "2" smd circle
			(at -0.40005 0 90)
			(size 0 0)
			(layers "B.Cu" "B.Mask" "B.Paste")
			(net "PVDDIO_P1")
		)
	)
	(footprint ""
		(layer "B.Cu")
		(at 89.614502 -207.41005 90)
		(property "Reference" "R928"
			(at 0 0 90)
			(layer "B.SilkS")
			(hide yes)
			(effects
				(font
					(size 1.27 1.27)
				)
				(justify mirror)
			)
		)
		(property "Value" ""
			(at 0 0 90)
			(layer "B.Fab")
			(effects
				(font
					(size 1.27 1.27)
				)
				(justify mirror)
			)
		)
		(duplicate_pad_numbers_are_jumpers no)
		(fp_line
			(start 0.7874 -0.4064)
			(end -0.7874 -0.4064)
			(stroke
				(width 0.1524)
				(type default)
			)
			(layer "B.SilkS")
		)
		(fp_line
			(start -0.7874 -0.4064)
			(end -0.7874 0.4064)
			(stroke
				(width 0.1524)
				(type default)
			)
			(layer "B.SilkS")
		)
		(fp_line
			(start 0.7874 0.4064)
			(end 0.7874 -0.4064)
			(stroke
				(width 0.1524)
				(type default)
			)
			(layer "B.SilkS")
		)
		(fp_line
			(start -0.7874 0.4064)
			(end 0.7874 0.4064)
			(stroke
				(width 0.1524)
				(type default)
			)
			(layer "B.SilkS")
		)
		(fp_line
			(start 0.67945 -0.305054)
			(end 0.12065 -0.305054)
			(stroke
				(width 0.1)
				(type default)
			)
			(layer "B.Fab")
		)
		(fp_line
			(start 0.12065 -0.305054)
			(end 0.12065 -0.2794)
			(stroke
				(width 0.1)
				(type default)
			)
			(layer "B.Fab")
		)
		(fp_line
			(start -0.12065 -0.3048)
			(end -0.67945 -0.3048)
			(stroke
				(width 0.1)
				(type default)
			)
			(layer "B.Fab")
		)
		(fp_line
			(start -0.67945 -0.3048)
			(end -0.67945 0.3048)
			(stroke
				(width 0.1)
				(type default)
			)
			(layer "B.Fab")
		)
		(fp_line
			(start 0.12065 -0.2794)
			(end -0.12065 -0.2794)
			(stroke
				(width 0.1)
				(type default)
			)
			(layer "B.Fab")
		)
		(fp_line
			(start -0.12065 -0.2794)
			(end -0.12065 -0.3048)
			(stroke
				(width 0.1)
				(type default)
			)
			(layer "B.Fab")
		)
		(fp_line
			(start 0.12065 0.2794)
			(end 0.12065 0.3048)
			(stroke
				(width 0.1)
				(type default)
			)
			(layer "B.Fab")
		)
		(fp_line
			(start -0.120396 0.2794)
			(end 0.12065 0.2794)
			(stroke
				(width 0.1)
				(type default)
			)
			(layer "B.Fab")
		)
		(fp_line
			(start 0.67945 0.3048)
			(end 0.67945 -0.305054)
			(stroke
				(width 0.1)
				(type default)
			)
			(layer "B.Fab")
		)
		(fp_line
			(start 0.12065 0.3048)
			(end 0.67945 0.3048)
			(stroke
				(width 0.1)
				(type default)
			)
			(layer "B.Fab")
		)
		(fp_line
			(start -0.120396 0.3048)
			(end -0.120396 0.2794)
			(stroke
				(width 0.1)
				(type default)
			)
			(layer "B.Fab")
		)
		(fp_line
			(start -0.67945 0.3048)
			(end -0.120396 0.3048)
			(stroke
				(width 0.1)
				(type default)
			)
			(layer "B.Fab")
		)
		(pad "1" smd circle
			(at 0.40005 0 270)
			(size 0 0)
			(layers "B.Cu" "B.Mask" "B.Paste")
			(net "CPU1_XTRIG_R2_L7")
		)
		(pad "2" smd circle
			(at -0.40005 0 270)
			(size 0 0)
			(layers "B.Cu" "B.Mask" "B.Paste")
			(net "CPU1_XTRIG_L7")
		)
	)
)
